# TIMECARD (Time Appliance Project (Time Card)) — schematic netlist excerpt (pin names and nets, part order shuffled) for the footprints in the layout excerpt that follows; sources: Cadence DE-HDL packaged netlist, KiCad conversion of R4006-B0001-02_R01.brd

R270  RESISTOR  4.7KOHM 1%  pkg SMC_0402R_H016  page 11 : \1\ = SG ; \2\ = FPGA_IN_GPSTP1_OUT
R216  RESISTOR  1KOHM 1%  pkg SMC_0402R_H016  page 10 : \1\ = FPGA_BRD_REV1 ; \2\ = SG

(kicad_pcb
	(version 20260206)
	(generator "pcbnew")
	(generator_version "10.0")
	(general
		(thickness 1.6)
		(legacy_teardrops no)
	)
	(paper "A4")
	(title_block
		(title "timecard-production-celestica-r4006 — R4006-B0001-02_R01.brd")
		(comment 1 "Time Appliance Project (Time Card) / footprints 869-870 of 1113")
	)
	(layers
		(0 "F.Cu" signal "TOP")
		(4 "In1.Cu" signal "L02_GND1")
		(6 "In2.Cu" signal "L03_SIG1")
		(8 "In3.Cu" signal "L04_GND2")
		(10 "In4.Cu" signal "L05_VCC1")
		(12 "In5.Cu" signal "L06_VCC2")
		(14 "In6.Cu" signal "L07_GND3")
		(16 "In7.Cu" signal "L08_SIG2")
		(18 "In8.Cu" signal "L09_GND4")
		(2 "B.Cu" signal "BOTTOM")
		(9 "F.Adhes" user "F.Adhesive")
		(11 "B.Adhes" user "B.Adhesive")
		(13 "F.Paste" user "Package Geometry/Pastemask Top")
		(15 "B.Paste" user "Package Geometry/Pastemask Bottom")
		(5 "F.SilkS" user "Ref Des/Silkscreen Top")
		(7 "B.SilkS" user "Ref Des/Silkscreen Bottom")
		(1 "F.Mask" user "Board Geometry/Soldermask Top")
		(3 "B.Mask" user "Board Geometry/Soldermask Bottom")
		(17 "Dwgs.User" user "User.Drawings")
		(19 "Cmts.User" user "User.Comments")
		(21 "Eco1.User" user "User.Eco1")
		(23 "Eco2.User" user "User.Eco2")
		(25 "Edge.Cuts" user "Board Geometry/Outline")
		(27 "Margin" user)
		(31 "F.CrtYd" user "Package Geometry/Place Bound Top")
		(29 "B.CrtYd" user "Package Geometry/Place Bound Bottom")
		(35 "F.Fab" user "Ref Des/Assembly Top")
		(33 "B.Fab" user "Ref Des/Assembly Bottom")
	)
	(footprint ""
		(layer "B.Cu")
		(at 116.34724 -47.82312 180)
		(property "Reference" "R270"
			(at 42.94124 -2.71907 0)
			(unlocked yes)
			(layer "B.SilkS")
			(effects
				(font
					(size 0.635 0.4064)
					(thickness 0.1524)
				)
				(justify mirror)
			)
		)
		(property "Value" "VAL*"
			(at 0 3.718306 180)
			(unlocked yes)
			(layer "B.Fab")
			(hide yes)
			(effects
				(font
					(size 0.7874 0.5842)
					(thickness 0.127)
				)
				(justify mirror)
			)
		)
		(property "Tolerance" "TOL*"
			(at 0 4.861306 180)
			(unlocked yes)
			(layer "Cmts.User")
			(hide yes)
			(effects
				(font
					(size 0.7874 0.5842)
					(thickness 0.127)
				)
				(justify mirror)
			)
		)
		(property "User Part Number" "PARTNUM*"
			(at 0 2.575306 180)
			(unlocked yes)
			(layer "Cmts.User")
			(hide yes)
			(effects
				(font
					(size 0.7874 0.5842)
					(thickness 0.127)
				)
				(justify mirror)
			)
		)
		(property "Device Type" "RESISTOR-G155-14701-01,4.7KOHMA"
			(at 0 1.432306 180)
			(unlocked yes)
			(layer "B.Fab")
			(hide yes)
			(effects
				(font
					(size 0.7874 0.5842)
					(thickness 0.127)
				)
				(justify mirror)
			)
		)
		(duplicate_pad_numbers_are_jumpers no)
		(fp_line
			(start 0.970026 0.4699)
			(end 0.970026 -0.4699)
			(stroke
				(width 0.1)
				(type default)
			)
			(layer "B.SilkS")
		)
		(fp_line
			(start 0.970026 -0.4699)
			(end -0.970026 -0.4699)
			(stroke
				(width 0.1)
				(type default)
			)
			(layer "B.SilkS")
		)
		(fp_line
			(start -0.970026 0.4699)
			(end 0.970026 0.4699)
			(stroke
				(width 0.1)
				(type default)
			)
			(layer "B.SilkS")
		)
		(fp_line
			(start -0.970026 -0.4699)
			(end -0.970026 0.4699)
			(stroke
				(width 0.1)
				(type default)
			)
			(layer "B.SilkS")
		)
		(fp_poly
			(pts
				(xy 0.970026 0.4699) (xy -0.970026 0.4699) (xy -0.970026 -0.4699) (xy 0.970026 -0.4699)
			)
			(stroke
				(width 0)
				(type default)
			)
			(fill no)
			(layer "B.CrtYd")
		)
		(fp_line
			(start 0.508 0.3048)
			(end 0.508 -0.3048)
			(stroke
				(width 0.1)
				(type default)
			)
			(layer "B.Fab")
		)
		(fp_line
			(start 0.508 -0.3048)
			(end -0.508 -0.3048)
			(stroke
				(width 0.1)
				(type default)
			)
			(layer "B.Fab")
		)
		(fp_line
			(start -0.508 0.3048)
			(end 0.508 0.3048)
			(stroke
				(width 0.1)
				(type default)
			)
			(layer "B.Fab")
		)
		(fp_line
			(start -0.508 -0.3048)
			(end -0.508 0.3048)
			(stroke
				(width 0.1)
				(type default)
			)
			(layer "B.Fab")
		)
		(pad "1" smd circle
			(at 0.500126 0)
			(size 0.635 0.635)
			(layers "B.Cu" "B.Mask" "B.Paste")
			(net "SG")
		)
		(pad "2" smd circle
			(at -0.500126 0)
			(size 0.635 0.635)
			(layers "B.Cu" "B.Mask" "B.Paste")
			(net "FPGA_IN_GPSTP1_OUT")
		)
	)
	(footprint ""
		(layer "B.Cu")
		(at 113.919 -61.976 -90)
		(property "Reference" "R216"
			(at -3.429 -0.08763 270)
			(unlocked yes)
			(layer "B.SilkS")
			(effects
				(font
					(size 0.7874 0.5842)
					(thickness 0.1524)
				)
				(justify mirror)
			)
		)
		(property "Value" "VAL*"
			(at -0.02032 2.13233 270)
			(unlocked yes)
			(layer "B.Fab")
			(hide yes)
			(effects
				(font
					(size 0.7874 0.5842)
					(thickness 0.1524)
				)
				(justify mirror)
			)
		)
		(property "Device Type" "RESISTOR-G155-11001-01,1KOHM,1%"
			(at -0.008382 1.210564 270)
			(unlocked yes)
			(layer "B.Fab")
			(hide yes)
			(effects
				(font
					(size 0.7874 0.5842)
					(thickness 0.1524)
				)
				(justify mirror)
			)
		)
		(property "User Part Number" "PARTNUM*"
			(at -0.02032 4.024884 270)
			(unlocked yes)
			(layer "Cmts.User")
			(hide yes)
			(effects
				(font
					(size 0.7874 0.5842)
					(thickness 0.1524)
				)
				(justify mirror)
			)
		)
		(property "Tolerance" "TOL*"
			(at -0.044704 3.05435 270)
			(unlocked yes)
			(layer "Cmts.User")
			(hide yes)
			(effects
				(font
					(size 0.7874 0.5842)
					(thickness 0.1524)
				)
				(justify mirror)
			)
		)
		(duplicate_pad_numbers_are_jumpers no)
		(fp_line
			(start -1.143 0.5588)
			(end -1.143 -0.5588)
			(stroke
				(width 0.1)
				(type default)
			)
			(layer "B.SilkS")
		)
		(fp_line
			(start 1.143 0.5588)
			(end -1.143 0.5588)
			(stroke
				(width 0.1)
				(type default)
			)
			(layer "B.SilkS")
		)
		(fp_line
			(start -1.143 -0.5588)
			(end 1.143 -0.5588)
			(stroke
				(width 0.1)
				(type default)
			)
			(layer "B.SilkS")
		)
		(fp_line
			(start 1.143 -0.5588)
			(end 1.143 0.5588)
			(stroke
				(width 0.1)
				(type default)
			)
			(layer "B.SilkS")
		)
		(fp_rect
			(start 1.143 0.5588)
			(end -1.143 -0.5588)
			(stroke
				(width 0)
				(type default)
			)
			(fill no)
			(layer "B.CrtYd")
		)
		(fp_line
			(start -0.508 0.3048)
			(end -0.508 -0.3048)
			(stroke
				(width 0.1)
				(type default)
			)
			(layer "B.Fab")
		)
		(fp_line
			(start 0.508 0.3048)
			(end -0.508 0.3048)
			(stroke
				(width 0.1)
				(type default)
			)
			(layer "B.Fab")
		)
		(fp_line
			(start -0.508 -0.3048)
			(end 0.508 -0.3048)
			(stroke
				(width 0.1)
				(type default)
			)
			(layer "B.Fab")
		)
		(fp_line
			(start 0.508 -0.3048)
			(end 0.508 0.3048)
			(stroke
				(width 0.1)
				(type default)
			)
			(layer "B.Fab")
		)
		(pad "1" smd rect
			(at 0.5334 0 90)
			(size 0.7112 0.6096)
			(layers "B.Cu" "B.Mask" "B.Paste")
			(net "FPGA_BRD_REV1")
		)
		(pad "2" smd rect
			(at -0.5334 0 90)
			(size 0.7112 0.6096)
			(layers "B.Cu" "B.Mask" "B.Paste")
			(net "SG")
		)
		(zone
			(layer "B.Cu")
			(hatch none 0.5)
			(connect_pads
				(clearance 0)
			)
			(min_thickness 0.25)
			(keepout
				(tracks allowed)
				(vias not_allowed)
				(pads allowed)
				(copperpour not_allowed)
				(footprints allowed)
			)
			(placement
				(enabled no)
				(sheetname "")
			)
			(fill
				(thermal_gap 0.5)
				(thermal_bridge_width 0.5)
				(island_removal_mode 0)
			)
			(polygon
				(pts
					(xy 113.6142 -61.8998) (xy 114.2238 -61.8998) (xy 114.2238 -62.0522) (xy 113.6142 -62.0522)
				)
			)
		)
	)
)
